# T6G (Grand Teton) — schematic netlist excerpt (pin names and nets, part order shuffled) for the footprints in the layout excerpt that follows; sources: Cadence DE-HDL packaged netlist, KiCad conversion of 04192023_DAF0TMB3IC0_F0TG_MB_C_brd_V02_OCP.brd

R1316  Q_RES  2.2K 5% CHIP  pkg 0402LF  page 252 : A = P3V3_AUX ; B = SMB_ADC_SCL_R
C7033  Q_CAP  47UF 4V 20% X6S  pkg C0805  page 279 : A = P0V9_CPU0_RT_2D ; B = GND
R1150  Q_RES  10K 1% CHIP  pkg 0402LF  page 134 : A = P3V3_AUX ; B = HP_LVC3_OCP_SFF_PRSNT2_PLD_N

(kicad_pcb
	(version 20260206)
	(generator "pcbnew")
	(generator_version "10.0")
	(general
		(thickness 1.6)
		(legacy_teardrops no)
	)
	(paper "A4")
	(title_block
		(title "04192023_DAF0TMB3IC0_F0TG_MB_C_brd_V02_OCP.brd")
		(comment 1 "Grand Teton / footprints 456-458 of 8354")
	)
	(layers
		(0 "F.Cu" signal "TOP")
		(4 "In1.Cu" signal "GND")
		(6 "In2.Cu" signal "IN1")
		(8 "In3.Cu" signal "GND1")
		(10 "In4.Cu" signal "IN2")
		(12 "In5.Cu" signal "GND2")
		(14 "In6.Cu" signal "IN3")
		(16 "In7.Cu" signal "GND3")
		(18 "In8.Cu" signal "VCC")
		(20 "In9.Cu" signal "VCC1")
		(22 "In10.Cu" signal "GND4")
		(24 "In11.Cu" signal "IN4")
		(26 "In12.Cu" signal "GND5")
		(28 "In13.Cu" signal "IN5")
		(30 "In14.Cu" signal "GND6")
		(32 "In15.Cu" signal "IN6")
		(34 "In16.Cu" signal "GND7")
		(2 "B.Cu" signal "BOTTOM")
		(9 "F.Adhes" user "F.Adhesive")
		(11 "B.Adhes" user "B.Adhesive")
		(13 "F.Paste" user "Package Geometry/Pastemask Top")
		(15 "B.Paste" user "Package Geometry/Pastemask Bottom")
		(5 "F.SilkS" user "Ref Des/Silkscreen Top")
		(7 "B.SilkS" user "Ref Des/Silkscreen Bottom")
		(1 "F.Mask" user "Board Geometry/Soldermask Top")
		(3 "B.Mask" user "Board Geometry/Soldermask Bottom")
		(17 "Dwgs.User" user "User.Drawings")
		(19 "Cmts.User" user "User.Comments")
		(21 "Eco1.User" user "User.Eco1")
		(23 "Eco2.User" user "User.Eco2")
		(25 "Edge.Cuts" user "Board Geometry/Outline")
		(27 "Margin" user)
		(31 "F.CrtYd" user "Package Geometry/Place Bound Top")
		(29 "B.CrtYd" user "Package Geometry/Place Bound Bottom")
		(35 "F.Fab" user "Ref Des/Assembly Top")
		(33 "B.Fab" user "Ref Des/Assembly Bottom")
	)
	(footprint ""
		(layer "F.Cu")
		(at 463.371946 -108.567728 180)
		(property "Reference" "R1150"
			(at 0 0 180)
			(layer "F.SilkS")
			(hide yes)
			(effects
				(font
					(size 1.27 1.27)
				)
			)
		)
		(property "Value" ""
			(at 0 0 180)
			(layer "F.Fab")
			(effects
				(font
					(size 1.27 1.27)
				)
			)
		)
		(duplicate_pad_numbers_are_jumpers no)
		(fp_line
			(start 0.7874 0.4064)
			(end -0.7874 0.4064)
			(stroke
				(width 0.1524)
				(type default)
			)
			(layer "F.SilkS")
		)
		(fp_line
			(start 0.7874 -0.4064)
			(end 0.7874 0.4064)
			(stroke
				(width 0.1524)
				(type default)
			)
			(layer "F.SilkS")
		)
		(fp_line
			(start -0.7874 0.4064)
			(end -0.7874 -0.4064)
			(stroke
				(width 0.1524)
				(type default)
			)
			(layer "F.SilkS")
		)
		(fp_line
			(start -0.7874 -0.4064)
			(end 0.7874 -0.4064)
			(stroke
				(width 0.1524)
				(type default)
			)
			(layer "F.SilkS")
		)
		(fp_line
			(start 0.67945 0.3048)
			(end 0.120396 0.3048)
			(stroke
				(width 0.1)
				(type default)
			)
			(layer "F.Fab")
		)
		(fp_line
			(start 0.67945 -0.3048)
			(end 0.67945 0.3048)
			(stroke
				(width 0.1)
				(type default)
			)
			(layer "F.Fab")
		)
		(fp_line
			(start 0.12065 -0.2794)
			(end 0.12065 -0.3048)
			(stroke
				(width 0.1)
				(type default)
			)
			(layer "F.Fab")
		)
		(fp_line
			(start 0.12065 -0.3048)
			(end 0.67945 -0.3048)
			(stroke
				(width 0.1)
				(type default)
			)
			(layer "F.Fab")
		)
		(fp_line
			(start 0.120396 0.3048)
			(end 0.120396 0.2794)
			(stroke
				(width 0.1)
				(type default)
			)
			(layer "F.Fab")
		)
		(fp_line
			(start 0.120396 0.2794)
			(end -0.12065 0.2794)
			(stroke
				(width 0.1)
				(type default)
			)
			(layer "F.Fab")
		)
		(fp_line
			(start -0.12065 0.3048)
			(end -0.67945 0.3048)
			(stroke
				(width 0.1)
				(type default)
			)
			(layer "F.Fab")
		)
		(fp_line
			(start -0.12065 0.2794)
			(end -0.12065 0.3048)
			(stroke
				(width 0.1)
				(type default)
			)
			(layer "F.Fab")
		)
		(fp_line
			(start -0.12065 -0.2794)
			(end 0.12065 -0.2794)
			(stroke
				(width 0.1)
				(type default)
			)
			(layer "F.Fab")
		)
		(fp_line
			(start -0.12065 -0.305054)
			(end -0.12065 -0.2794)
			(stroke
				(width 0.1)
				(type default)
			)
			(layer "F.Fab")
		)
		(fp_line
			(start -0.67945 0.3048)
			(end -0.67945 -0.305054)
			(stroke
				(width 0.1)
				(type default)
			)
			(layer "F.Fab")
		)
		(fp_line
			(start -0.67945 -0.305054)
			(end -0.12065 -0.305054)
			(stroke
				(width 0.1)
				(type default)
			)
			(layer "F.Fab")
		)
		(pad "1" smd circle
			(at -0.40005 0 180)
			(size 0 0)
			(layers "F.Cu" "F.Mask" "F.Paste")
			(net "P3V3_AUX")
		)
		(pad "2" smd circle
			(at 0.40005 0 180)
			(size 0 0)
			(layers "F.Cu" "F.Mask" "F.Paste")
			(net "HP_LVC3_OCP_SFF_PRSNT2_PLD_N")
		)
	)
	(footprint ""
		(layer "F.Cu")
		(at 306.262532 -410.406596 90)
		(property "Reference" "C7033"
			(at 0 0 90)
			(layer "F.SilkS")
			(hide yes)
			(effects
				(font
					(size 1.27 1.27)
				)
			)
		)
		(property "Value" ""
			(at 0 0 90)
			(layer "F.Fab")
			(effects
				(font
					(size 1.27 1.27)
				)
			)
		)
		(duplicate_pad_numbers_are_jumpers no)
		(fp_line
			(start 1.524 -0.762)
			(end 1.524 0.762)
			(stroke
				(width 0.1524)
				(type default)
			)
			(layer "F.SilkS")
		)
		(fp_line
			(start -1.524 -0.762)
			(end 1.524 -0.762)
			(stroke
				(width 0.1524)
				(type default)
			)
			(layer "F.SilkS")
		)
		(fp_line
			(start 1.524 0.762)
			(end -1.524 0.762)
			(stroke
				(width 0.1524)
				(type default)
			)
			(layer "F.SilkS")
		)
		(fp_line
			(start -1.524 0.762)
			(end -1.524 -0.762)
			(stroke
				(width 0.1524)
				(type default)
			)
			(layer "F.SilkS")
		)
		(fp_line
			(start 1.1049 -0.724916)
			(end -1.1049 -0.724916)
			(stroke
				(width 0.1)
				(type default)
			)
			(layer "F.Fab")
		)
		(fp_line
			(start -1.1049 -0.724916)
			(end -1.1049 0.724916)
			(stroke
				(width 0.1)
				(type default)
			)
			(layer "F.Fab")
		)
		(fp_line
			(start 1.1049 0.724916)
			(end 1.1049 -0.724916)
			(stroke
				(width 0.1)
				(type default)
			)
			(layer "F.Fab")
		)
		(fp_line
			(start -1.1049 0.724916)
			(end 1.1049 0.724916)
			(stroke
				(width 0.1)
				(type default)
			)
			(layer "F.Fab")
		)
		(pad "1" smd rect
			(at -0.889 0 270)
			(size 1.016 1.27)
			(layers "F.Cu" "F.Mask" "F.Paste")
			(net "P0V9_CPU0_RT_2D")
		)
		(pad "2" smd rect
			(at 0.889 0 270)
			(size 1.016 1.27)
			(layers "F.Cu" "F.Mask" "F.Paste")
			(net "GND")
		)
	)
	(footprint ""
		(layer "F.Cu")
		(at 273.378676 -119.761 180)
		(property "Reference" "R1316"
			(at 0 0 180)
			(layer "F.SilkS")
			(hide yes)
			(effects
				(font
					(size 1.27 1.27)
				)
			)
		)
		(property "Value" ""
			(at 0 0 180)
			(layer "F.Fab")
			(effects
				(font
					(size 1.27 1.27)
				)
			)
		)
		(duplicate_pad_numbers_are_jumpers no)
		(fp_line
			(start 0.7874 0.4064)
			(end -0.7874 0.4064)
			(stroke
				(width 0.1524)
				(type default)
			)
			(layer "F.SilkS")
		)
		(fp_line
			(start 0.7874 -0.4064)
			(end 0.7874 0.4064)
			(stroke
				(width 0.1524)
				(type default)
			)
			(layer "F.SilkS")
		)
		(fp_line
			(start -0.7874 0.4064)
			(end -0.7874 -0.4064)
			(stroke
				(width 0.1524)
				(type default)
			)
			(layer "F.SilkS")
		)
		(fp_line
			(start -0.7874 -0.4064)
			(end 0.7874 -0.4064)
			(stroke
				(width 0.1524)
				(type default)
			)
			(layer "F.SilkS")
		)
		(fp_line
			(start 0.67945 0.3048)
			(end 0.120396 0.3048)
			(stroke
				(width 0.1)
				(type default)
			)
			(layer "F.Fab")
		)
		(fp_line
			(start 0.67945 -0.3048)
			(end 0.67945 0.3048)
			(stroke
				(width 0.1)
				(type default)
			)
			(layer "F.Fab")
		)
		(fp_line
			(start 0.12065 -0.2794)
			(end 0.12065 -0.3048)
			(stroke
				(width 0.1)
				(type default)
			)
			(layer "F.Fab")
		)
		(fp_line
			(start 0.12065 -0.3048)
			(end 0.67945 -0.3048)
			(stroke
				(width 0.1)
				(type default)
			)
			(layer "F.Fab")
		)
		(fp_line
			(start 0.120396 0.3048)
			(end 0.120396 0.2794)
			(stroke
				(width 0.1)
				(type default)
			)
			(layer "F.Fab")
		)
		(fp_line
			(start 0.120396 0.2794)
			(end -0.12065 0.2794)
			(stroke
				(width 0.1)
				(type default)
			)
			(layer "F.Fab")
		)
		(fp_line
			(start -0.12065 0.3048)
			(end -0.67945 0.3048)
			(stroke
				(width 0.1)
				(type default)
			)
			(layer "F.Fab")
		)
		(fp_line
			(start -0.12065 0.2794)
			(end -0.12065 0.3048)
			(stroke
				(width 0.1)
				(type default)
			)
			(layer "F.Fab")
		)
		(fp_line
			(start -0.12065 -0.2794)
			(end 0.12065 -0.2794)
			(stroke
				(width 0.1)
				(type default)
			)
			(layer "F.Fab")
		)
		(fp_line
			(start -0.12065 -0.305054)
			(end -0.12065 -0.2794)
			(stroke
				(width 0.1)
				(type default)
			)
			(layer "F.Fab")
		)
		(fp_line
			(start -0.67945 0.3048)
			(end -0.67945 -0.305054)
			(stroke
				(width 0.1)
				(type default)
			)
			(layer "F.Fab")
		)
		(fp_line
			(start -0.67945 -0.305054)
			(end -0.12065 -0.305054)
			(stroke
				(width 0.1)
				(type default)
			)
			(layer "F.Fab")
		)
		(pad "1" smd circle
			(at -0.40005 0 180)
			(size 0 0)
			(layers "F.Cu" "F.Mask" "F.Paste")
			(net "P3V3_AUX")
		)
		(pad "2" smd circle
			(at 0.40005 0 180)
			(size 0 0)
			(layers "F.Cu" "F.Mask" "F.Paste")
			(net "SMB_ADC_SCL_R")
		)
	)
)
